# T6G (Grand Teton) — schematic netlist excerpt (pin names and nets, part order shuffled) for the footprints in the layout excerpt that follows; sources: Cadence DE-HDL packaged netlist, KiCad conversion of 04192023_DAF0TMB3IC0_F0TG_MB_C_brd_V02_OCP.brd

U11  M24M02DRMN6TP  M24M02-DRMN6TP IC  pkg SOIC8XH  page 278
  DU1  = NC
  DU2  = NC
  E2  = U11_E2
  VSS  = GND
  SDA  = SMB_RT_CPU0_P0_ROM_SDA
  SCL  = SMB_RT_CPU0_P0_ROM_SCL
  WC_N  = GND
  VCC  = P1V8_CPU0_RT_1D

R135  Q_RES  4.7K 5% EMPTY  pkg 0402LF  page 83 : A = FM_APML_MUX2_SEL ; B = P3V3_AUX

(kicad_pcb
	(version 20260206)
	(generator "pcbnew")
	(generator_version "10.0")
	(general
		(thickness 1.6)
		(legacy_teardrops no)
	)
	(paper "A4")
	(title_block
		(title "04192023_DAF0TMB3IC0_F0TG_MB_C_brd_V02_OCP.brd")
		(comment 1 "Grand Teton / footprints 3968-3969 of 8354")
	)
	(layers
		(0 "F.Cu" signal "TOP")
		(4 "In1.Cu" signal "GND")
		(6 "In2.Cu" signal "IN1")
		(8 "In3.Cu" signal "GND1")
		(10 "In4.Cu" signal "IN2")
		(12 "In5.Cu" signal "GND2")
		(14 "In6.Cu" signal "IN3")
		(16 "In7.Cu" signal "GND3")
		(18 "In8.Cu" signal "VCC")
		(20 "In9.Cu" signal "VCC1")
		(22 "In10.Cu" signal "GND4")
		(24 "In11.Cu" signal "IN4")
		(26 "In12.Cu" signal "GND5")
		(28 "In13.Cu" signal "IN5")
		(30 "In14.Cu" signal "GND6")
		(32 "In15.Cu" signal "IN6")
		(34 "In16.Cu" signal "GND7")
		(2 "B.Cu" signal "BOTTOM")
		(9 "F.Adhes" user "F.Adhesive")
		(11 "B.Adhes" user "B.Adhesive")
		(13 "F.Paste" user "Package Geometry/Pastemask Top")
		(15 "B.Paste" user "Package Geometry/Pastemask Bottom")
		(5 "F.SilkS" user "Ref Des/Silkscreen Top")
		(7 "B.SilkS" user "Ref Des/Silkscreen Bottom")
		(1 "F.Mask" user "Board Geometry/Soldermask Top")
		(3 "B.Mask" user "Board Geometry/Soldermask Bottom")
		(17 "Dwgs.User" user "User.Drawings")
		(19 "Cmts.User" user "User.Comments")
		(21 "Eco1.User" user "User.Eco1")
		(23 "Eco2.User" user "User.Eco2")
		(25 "Edge.Cuts" user "Board Geometry/Outline")
		(27 "Margin" user)
		(31 "F.CrtYd" user "Package Geometry/Place Bound Top")
		(29 "B.CrtYd" user "Package Geometry/Place Bound Bottom")
		(35 "F.Fab" user "Ref Des/Assembly Top")
		(33 "B.Fab" user "Ref Des/Assembly Bottom")
	)
	(footprint ""
		(layer "F.Cu")
		(at 212.993732 -115.716812 180)
		(property "Reference" "R135"
			(at 0 0 180)
			(layer "F.SilkS")
			(hide yes)
			(effects
				(font
					(size 1.27 1.27)
				)
			)
		)
		(property "Value" ""
			(at 0 0 180)
			(layer "F.Fab")
			(effects
				(font
					(size 1.27 1.27)
				)
			)
		)
		(duplicate_pad_numbers_are_jumpers no)
		(fp_line
			(start 0.7874 0.4064)
			(end -0.7874 0.4064)
			(stroke
				(width 0.1524)
				(type default)
			)
			(layer "F.SilkS")
		)
		(fp_line
			(start 0.7874 -0.4064)
			(end 0.7874 0.4064)
			(stroke
				(width 0.1524)
				(type default)
			)
			(layer "F.SilkS")
		)
		(fp_line
			(start -0.7874 0.4064)
			(end -0.7874 -0.4064)
			(stroke
				(width 0.1524)
				(type default)
			)
			(layer "F.SilkS")
		)
		(fp_line
			(start -0.7874 -0.4064)
			(end 0.7874 -0.4064)
			(stroke
				(width 0.1524)
				(type default)
			)
			(layer "F.SilkS")
		)
		(fp_line
			(start 0.67945 0.3048)
			(end 0.120396 0.3048)
			(stroke
				(width 0.1)
				(type default)
			)
			(layer "F.Fab")
		)
		(fp_line
			(start 0.67945 -0.3048)
			(end 0.67945 0.3048)
			(stroke
				(width 0.1)
				(type default)
			)
			(layer "F.Fab")
		)
		(fp_line
			(start 0.12065 -0.2794)
			(end 0.12065 -0.3048)
			(stroke
				(width 0.1)
				(type default)
			)
			(layer "F.Fab")
		)
		(fp_line
			(start 0.12065 -0.3048)
			(end 0.67945 -0.3048)
			(stroke
				(width 0.1)
				(type default)
			)
			(layer "F.Fab")
		)
		(fp_line
			(start 0.120396 0.3048)
			(end 0.120396 0.2794)
			(stroke
				(width 0.1)
				(type default)
			)
			(layer "F.Fab")
		)
		(fp_line
			(start 0.120396 0.2794)
			(end -0.12065 0.2794)
			(stroke
				(width 0.1)
				(type default)
			)
			(layer "F.Fab")
		)
		(fp_line
			(start -0.12065 0.3048)
			(end -0.67945 0.3048)
			(stroke
				(width 0.1)
				(type default)
			)
			(layer "F.Fab")
		)
		(fp_line
			(start -0.12065 0.2794)
			(end -0.12065 0.3048)
			(stroke
				(width 0.1)
				(type default)
			)
			(layer "F.Fab")
		)
		(fp_line
			(start -0.12065 -0.2794)
			(end 0.12065 -0.2794)
			(stroke
				(width 0.1)
				(type default)
			)
			(layer "F.Fab")
		)
		(fp_line
			(start -0.12065 -0.305054)
			(end -0.12065 -0.2794)
			(stroke
				(width 0.1)
				(type default)
			)
			(layer "F.Fab")
		)
		(fp_line
			(start -0.67945 0.3048)
			(end -0.67945 -0.305054)
			(stroke
				(width 0.1)
				(type default)
			)
			(layer "F.Fab")
		)
		(fp_line
			(start -0.67945 -0.305054)
			(end -0.12065 -0.305054)
			(stroke
				(width 0.1)
				(type default)
			)
			(layer "F.Fab")
		)
		(pad "1" smd circle
			(at -0.40005 0 180)
			(size 0 0)
			(layers "F.Cu" "F.Mask" "F.Paste")
			(net "FM_APML_MUX2_SEL")
		)
		(pad "2" smd circle
			(at 0.40005 0 180)
			(size 0 0)
			(layers "F.Cu" "F.Mask" "F.Paste")
			(net "P3V3_AUX")
		)
	)
	(footprint ""
		(layer "F.Cu")
		(at 298.878498 -424.78833 -90)
		(property "Reference" "U11"
			(at 0.413766 3.240532 90)
			(unlocked yes)
			(layer "F.SilkS")
			(effects
				(font
					(size 0.7874 0.5842)
					(thickness 0.1524)
				)
				(justify left)
			)
		)
		(property "Value" ""
			(at 0 0 270)
			(layer "F.Fab")
			(effects
				(font
					(size 1.27 1.27)
				)
			)
		)
		(duplicate_pad_numbers_are_jumpers no)
		(fp_line
			(start -1.8288 2.500122)
			(end 1.8288 2.500122)
			(stroke
				(width 0.1524)
				(type default)
			)
			(layer "F.SilkS")
		)
		(fp_line
			(start 1.8288 2.500122)
			(end 1.8288 -2.500122)
			(stroke
				(width 0.1524)
				(type default)
			)
			(layer "F.SilkS")
		)
		(fp_line
			(start 0 -1.4224)
			(end -1.077722 -2.500122)
			(stroke
				(width 0.1524)
				(type default)
			)
			(layer "F.SilkS")
		)
		(fp_line
			(start -1.8288 -2.500122)
			(end -1.8288 2.500122)
			(stroke
				(width 0.1524)
				(type default)
			)
			(layer "F.SilkS")
		)
		(fp_line
			(start -1.077722 -2.500122)
			(end -1.8288 -2.500122)
			(stroke
				(width 0.1524)
				(type default)
			)
			(layer "F.SilkS")
		)
		(fp_line
			(start 1.077722 -2.500122)
			(end 0 -1.4224)
			(stroke
				(width 0.1524)
				(type default)
			)
			(layer "F.SilkS")
		)
		(fp_line
			(start 1.8288 -2.500122)
			(end 1.077722 -2.500122)
			(stroke
				(width 0.1524)
				(type default)
			)
			(layer "F.SilkS")
		)
		(fp_poly
			(pts
				(xy -4.41198 -2.683002) (xy -4.41198 -1.667002) (xy -3.39598 -2.175002)
			)
			(stroke
				(width 0)
				(type default)
			)
			(fill yes)
			(layer "F.SilkS")
		)
		(fp_line
			(start -1.999996 2.500122)
			(end 1.999996 2.500122)
			(stroke
				(width 0.1)
				(type default)
			)
			(layer "F.Fab")
		)
		(fp_line
			(start 1.999996 2.500122)
			(end 1.999996 -2.500122)
			(stroke
				(width 0.1)
				(type default)
			)
			(layer "F.Fab")
		)
		(fp_line
			(start -1.999996 -2.500122)
			(end -1.999996 2.500122)
			(stroke
				(width 0.1)
				(type default)
			)
			(layer "F.Fab")
		)
		(fp_line
			(start 1.999996 -2.500122)
			(end -1.999996 -2.500122)
			(stroke
				(width 0.1)
				(type default)
			)
			(layer "F.Fab")
		)
		(fp_poly
			(pts
				(xy -4.5085 -2.413) (xy -4.5085 -1.397) (xy -3.4925 -1.905)
			)
			(stroke
				(width 0)
				(type default)
			)
			(fill yes)
			(layer "F.Fab")
		)
		(pad "1" smd rect
			(at -2.599944 -1.905 180)
			(size 0.889 1.27)
			(layers "F.Cu" "F.Mask" "F.Paste")
			(net "Net_10847")
		)
		(pad "2" smd rect
			(at -2.599944 -0.635 180)
			(size 0.889 1.27)
			(layers "F.Cu" "F.Mask" "F.Paste")
			(net "Net_10846")
		)
		(pad "3" smd rect
			(at -2.599944 0.635 180)
			(size 0.889 1.27)
			(layers "F.Cu" "F.Mask" "F.Paste")
			(net "U11_E2")
		)
		(pad "4" smd rect
			(at -2.599944 1.905 180)
			(size 0.889 1.27)
			(layers "F.Cu" "F.Mask" "F.Paste")
			(net "GND")
		)
		(pad "5" smd rect
			(at 2.599944 1.905 180)
			(size 0.889 1.27)
			(layers "F.Cu" "F.Mask" "F.Paste")
			(net "SMB_RT_CPU0_P0_ROM_SDA")
		)
		(pad "6" smd rect
			(at 2.599944 0.635 180)
			(size 0.889 1.27)
			(layers "F.Cu" "F.Mask" "F.Paste")
			(net "SMB_RT_CPU0_P0_ROM_SCL")
		)
		(pad "7" smd rect
			(at 2.599944 -0.635 180)
			(size 0.889 1.27)
			(layers "F.Cu" "F.Mask" "F.Paste")
			(net "GND")
		)
		(pad "8" smd rect
			(at 2.599944 -1.905 180)
			(size 0.889 1.27)
			(layers "F.Cu" "F.Mask" "F.Paste")
			(net "P1V8_CPU0_RT_1D")
		)
	)
)
